(kicad_pcb
	(version 20241229)
	(generator "pcbnew")
	(generator_version "9.0")
	(general
		(thickness 1.61)
		(legacy_teardrops no)
	)
	(paper "A3")
	(title_block
		(title "RDIMM DDR5 Tester")
		(date "2026-05-21")
		(rev "2.2.0")
		(company "Antmicro")
		(comment 9 "footprints 688-692 of 796")
	)
	(layers
		(0 "F.Cu" signal)
		(4 "In1.Cu" power)
		(6 "In2.Cu" mixed)
		(8 "In3.Cu" power)
		(10 "In4.Cu" mixed)
		(12 "In5.Cu" power)
		(14 "In6.Cu" mixed)
		(16 "In7.Cu" power)
		(18 "In8.Cu" power)
		(20 "In9.Cu" mixed)
		(22 "In10.Cu" power)
		(2 "B.Cu" signal)
		(9 "F.Adhes" user "F.Adhesive")
		(11 "B.Adhes" user "B.Adhesive")
		(13 "F.Paste" user)
		(15 "B.Paste" user)
		(5 "F.SilkS" user "F.Silkscreen")
		(7 "B.SilkS" user "B.Silkscreen")
		(1 "F.Mask" user)
		(3 "B.Mask" user)
		(17 "Dwgs.User" user "User.Drawings")
		(19 "Cmts.User" user "User.Comments")
		(21 "Eco1.User" user "User.Eco1")
		(23 "Eco2.User" user "User.Eco2")
		(25 "Edge.Cuts" user)
		(27 "Margin" user)
		(31 "F.CrtYd" user "F.Courtyard")
		(29 "B.CrtYd" user "B.Courtyard")
		(35 "F.Fab" user)
		(33 "B.Fab" user)
	)
	(footprint "antmicro-footprints:C_0402_1005Metric"
		(layer "B.Cu")
		(at 149.084499 164.653 90)
		(descr "Capacitor SMD 0402")
		(tags "capacitor SMD 0402")
		(property "Reference" "C238"
			(at -3.749 0.521501 90)
			(layer "B.SilkS")
			(effects
				(font
					(size 0.7 0.7)
					(thickness 0.15)
				)
				(justify right bottom mirror)
			)
		)
		(property "Value" "C_100n_0402"
			(at -1.022927 -2.155213 90)
			(layer "B.Fab")
			(effects
				(font
					(size 0.7 0.7)
					(thickness 0.15)
				)
				(justify right bottom mirror)
			)
		)
		(property "Datasheet" "https://www.murata.com/products/productdetail?partno=GRM155R61H104KE14%23"
			(at 0 0 90)
			(layer "F.Fab")
			(hide yes)
			(effects
				(font
					(size 1.27 1.27)
					(thickness 0.15)
				)
			)
		)
		(property "MPN" "GRM155R61H104KE14D"
			(at 0 0 90)
			(unlocked yes)
			(layer "B.Fab")
			(hide yes)
			(effects
				(font
					(size 1 1)
					(thickness 0.15)
				)
				(justify mirror)
			)
		)
		(property "Manufacturer" "Murata"
			(at 0 0 90)
			(unlocked yes)
			(layer "B.Fab")
			(hide yes)
			(effects
				(font
					(size 1 1)
					(thickness 0.15)
				)
				(justify mirror)
			)
		)
		(property "License" "Apache-2.0"
			(at 0 0 90)
			(unlocked yes)
			(layer "B.Fab")
			(hide yes)
			(effects
				(font
					(size 1 1)
					(thickness 0.15)
				)
				(justify mirror)
			)
		)
		(property "Author" "Antmicro"
			(at 0 0 90)
			(unlocked yes)
			(layer "B.Fab")
			(hide yes)
			(effects
				(font
					(size 1 1)
					(thickness 0.15)
				)
				(justify mirror)
			)
		)
		(property "Val" "100n"
			(at 0 0 90)
			(unlocked yes)
			(layer "B.Fab")
			(hide yes)
			(effects
				(font
					(size 1 1)
					(thickness 0.15)
				)
				(justify mirror)
			)
		)
		(property "Voltage" "50V"
			(at 0 0 90)
			(unlocked yes)
			(layer "B.Fab")
			(hide yes)
			(effects
				(font
					(size 1 1)
					(thickness 0.15)
				)
				(justify mirror)
			)
		)
		(property "Dielectric" "X5R"
			(at 0 0 90)
			(unlocked yes)
			(layer "B.Fab")
			(hide yes)
			(effects
				(font
					(size 1 1)
					(thickness 0.15)
				)
				(justify mirror)
			)
		)
		(sheetname "/Debug FTDI + VNA/")
		(sheetfile "debug-ftdi.kicad_sch")
		(attr smd)
		(fp_rect
			(start -0.925 0.47)
			(end 0.925 -0.47)
			(stroke
				(width 0.05)
				(type default)
			)
			(fill no)
			(layer "B.CrtYd")
		)
		(fp_line
			(start 0.504 -0.248)
			(end -0.494 -0.248)
			(stroke
				(width 0.15)
				(type solid)
			)
			(layer "B.Fab")
		)
		(fp_line
			(start -0.494 -0.248)
			(end -0.494 0.25)
			(stroke
				(width 0.15)
				(type solid)
			)
			(layer "B.Fab")
		)
		(fp_line
			(start 0.504 0.25)
			(end 0.504 -0.248)
			(stroke
				(width 0.15)
				(type solid)
			)
			(layer "B.Fab")
		)
		(fp_line
			(start -0.494 0.25)
			(end 0.504 0.25)
			(stroke
				(width 0.15)
				(type solid)
			)
			(layer "B.Fab")
		)
		(fp_text user "${REFERENCE}"
			(at -0.939 -4.599 270)
			(layer "B.Fab")
			(effects
				(font
					(size 0.7 0.7)
					(thickness 0.15)
				)
				(justify left bottom mirror)
			)
		)
		(fp_text user "License: Apache-2.0"
			(at -0.939 -5.799 270)
			(layer "B.Fab")
			(effects
				(font
					(size 0.7 0.7)
					(thickness 0.15)
				)
				(justify left bottom mirror)
			)
		)
		(fp_text user "Author: Antmicro"
			(at -0.939 -3.399 270)
			(layer "B.Fab")
			(effects
				(font
					(size 0.7 0.7)
					(thickness 0.15)
				)
				(justify left bottom mirror)
			)
		)
		(pad "1" smd roundrect
			(at -0.48 0 90)
			(size 0.59 0.64)
			(layers "B.Cu" "B.Mask" "B.Paste")
			(roundrect_rratio 0.25)
			(net 1 "GND")
			(pintype "passive")
		)
		(pad "2" smd roundrect
			(at 0.48 0 90)
			(size 0.59 0.64)
			(layers "B.Cu" "B.Mask" "B.Paste")
			(roundrect_rratio 0.25)
			(net 151 "+3V3")
			(pintype "passive")
		)
	)
	(footprint "antmicro-footprints:C_0402_1005Metric"
		(layer "B.Cu")
		(at 120.411 167.35)
		(descr "Capacitor SMD 0402")
		(tags "capacitor SMD 0402")
		(property "Reference" "C82"
			(at 0.889 1.05 0)
			(layer "B.SilkS")
			(effects
				(font
					(size 0.7 0.7)
					(thickness 0.15)
				)
				(justify right bottom mirror)
			)
		)
		(property "Value" "C_100n_0402"
			(at -1.022927 -2.155213 0)
			(layer "B.Fab")
			(effects
				(font
					(size 0.7 0.7)
					(thickness 0.15)
				)
				(justify right bottom mirror)
			)
		)
		(property "Datasheet" "https://www.murata.com/products/productdetail?partno=GRM155R61H104KE14%23"
			(at 0 0 0)
			(layer "F.Fab")
			(hide yes)
			(effects
				(font
					(size 1.27 1.27)
					(thickness 0.15)
				)
			)
		)
		(property "MPN" "GRM155R61H104KE14D"
			(at 0 0 0)
			(unlocked yes)
			(layer "B.Fab")
			(hide yes)
			(effects
				(font
					(size 1 1)
					(thickness 0.15)
				)
				(justify mirror)
			)
		)
		(property "Manufacturer" "Murata"
			(at 0 0 0)
			(unlocked yes)
			(layer "B.Fab")
			(hide yes)
			(effects
				(font
					(size 1 1)
					(thickness 0.15)
				)
				(justify mirror)
			)
		)
		(property "License" "Apache-2.0"
			(at 0 0 0)
			(unlocked yes)
			(layer "B.Fab")
			(hide yes)
			(effects
				(font
					(size 1 1)
					(thickness 0.15)
				)
				(justify mirror)
			)
		)
		(property "Author" "Antmicro"
			(at 0 0 0)
			(unlocked yes)
			(layer "B.Fab")
			(hide yes)
			(effects
				(font
					(size 1 1)
					(thickness 0.15)
				)
				(justify mirror)
			)
		)
		(property "Val" "100n"
			(at 0 0 0)
			(unlocked yes)
			(layer "B.Fab")
			(hide yes)
			(effects
				(font
					(size 1 1)
					(thickness 0.15)
				)
				(justify mirror)
			)
		)
		(property "Voltage" "50V"
			(at 0 0 0)
			(unlocked yes)
			(layer "B.Fab")
			(hide yes)
			(effects
				(font
					(size 1 1)
					(thickness 0.15)
				)
				(justify mirror)
			)
		)
		(property "Dielectric" "X5R"
			(at 0 0 0)
			(unlocked yes)
			(layer "B.Fab")
			(hide yes)
			(effects
				(font
					(size 1 1)
					(thickness 0.15)
				)
				(justify mirror)
			)
		)
		(property "Public" ""
			(at 0 0 0)
			(unlocked yes)
			(layer "B.Fab")
			(hide yes)
			(effects
				(font
					(size 1 1)
					(thickness 0.15)
				)
				(justify mirror)
			)
		)
		(sheetname "/HDMI + SD Card/")
		(sheetfile "hdmi-sd-card.kicad_sch")
		(attr smd)
		(fp_rect
			(start -0.925 0.47)
			(end 0.925 -0.47)
			(stroke
				(width 0.05)
				(type default)
			)
			(fill no)
			(layer "B.CrtYd")
		)
		(fp_line
			(start -0.494 -0.248)
			(end -0.494 0.25)
			(stroke
				(width 0.15)
				(type solid)
			)
			(layer "B.Fab")
		)
		(fp_line
			(start -0.494 0.25)
			(end 0.504 0.25)
			(stroke
				(width 0.15)
				(type solid)
			)
			(layer "B.Fab")
		)
		(fp_line
			(start 0.504 -0.248)
			(end -0.494 -0.248)
			(stroke
				(width 0.15)
				(type solid)
			)
			(layer "B.Fab")
		)
		(fp_line
			(start 0.504 0.25)
			(end 0.504 -0.248)
			(stroke
				(width 0.15)
				(type solid)
			)
			(layer "B.Fab")
		)
		(fp_text user "Author: Antmicro"
			(at -0.939 -3.399 180)
			(layer "B.Fab")
			(effects
				(font
					(size 0.7 0.7)
					(thickness 0.15)
				)
				(justify left bottom mirror)
			)
		)
		(fp_text user "License: Apache-2.0"
			(at -0.939 -5.799 180)
			(layer "B.Fab")
			(effects
				(font
					(size 0.7 0.7)
					(thickness 0.15)
				)
				(justify left bottom mirror)
			)
		)
		(fp_text user "${REFERENCE}"
			(at -0.939 -4.599 180)
			(layer "B.Fab")
			(effects
				(font
					(size 0.7 0.7)
					(thickness 0.15)
				)
				(justify left bottom mirror)
			)
		)
		(pad "1" smd roundrect
			(at -0.48 0)
			(size 0.59 0.64)
			(layers "B.Cu" "B.Mask" "B.Paste")
			(roundrect_rratio 0.25)
			(net 151 "+3V3")
			(pintype "passive")
		)
		(pad "2" smd roundrect
			(at 0.48 0)
			(size 0.59 0.64)
			(layers "B.Cu" "B.Mask" "B.Paste")
			(roundrect_rratio 0.25)
			(net 1 "GND")
			(pintype "passive")
		)
	)
	(footprint "antmicro-footprints:C_0402_1005Metric"
		(layer "B.Cu")
		(at 164.03 154.5 -90)
		(descr "Capacitor SMD 0402")
		(tags "capacitor SMD 0402")
		(property "Reference" "C2"
			(at -2.4 -0.37 90)
			(layer "B.SilkS")
			(effects
				(font
					(size 0.7 0.7)
					(thickness 0.15)
				)
				(justify left bottom mirror)
			)
		)
		(property "Value" "C_100n_0402"
			(at -1.022927 -2.155213 90)
			(layer "B.Fab")
			(effects
				(font
					(size 0.7 0.7)
					(thickness 0.15)
				)
				(justify left bottom mirror)
			)
		)
		(property "Datasheet" "https://www.murata.com/products/productdetail?partno=GRM155R61H104KE14%23"
			(at 0 0 270)
			(layer "F.Fab")
			(hide yes)
			(effects
				(font
					(size 1.27 1.27)
					(thickness 0.15)
				)
			)
		)
		(property "Manufacturer" "Murata"
			(at 0 0 270)
			(unlocked yes)
			(layer "B.Fab")
			(hide yes)
			(effects
				(font
					(size 1 1)
					(thickness 0.15)
				)
				(justify mirror)
			)
		)
		(property "MPN" "GRM155R61H104KE14D"
			(at 0 0 270)
			(unlocked yes)
			(layer "B.Fab")
			(hide yes)
			(effects
				(font
					(size 1 1)
					(thickness 0.15)
				)
				(justify mirror)
			)
		)
		(property "Val" "100n"
			(at 0 0 270)
			(unlocked yes)
			(layer "B.Fab")
			(hide yes)
			(effects
				(font
					(size 1 1)
					(thickness 0.15)
				)
				(justify mirror)
			)
		)
		(property "License" "Apache-2.0"
			(at 0 0 270)
			(unlocked yes)
			(layer "B.Fab")
			(hide yes)
			(effects
				(font
					(size 1 1)
					(thickness 0.15)
				)
				(justify mirror)
			)
		)
		(property "Author" "Antmicro"
			(at 0 0 270)
			(unlocked yes)
			(layer "B.Fab")
			(hide yes)
			(effects
				(font
					(size 1 1)
					(thickness 0.15)
				)
				(justify mirror)
			)
		)
		(property "Voltage" "50V"
			(at 0 0 270)
			(unlocked yes)
			(layer "B.Fab")
			(hide yes)
			(effects
				(font
					(size 1 1)
					(thickness 0.15)
				)
				(justify mirror)
			)
		)
		(property "Dielectric" "X5R"
			(at 0 0 270)
			(unlocked yes)
			(layer "B.Fab")
			(hide yes)
			(effects
				(font
					(size 1 1)
					(thickness 0.15)
				)
				(justify mirror)
			)
		)
		(sheetname "/HyperRAM + QSPI Flash/")
		(sheetfile "hyperram-flash.kicad_sch")
		(attr smd)
		(fp_rect
			(start -0.925 0.47)
			(end 0.925 -0.47)
			(stroke
				(width 0.05)
				(type default)
			)
			(fill no)
			(layer "B.CrtYd")
		)
		(fp_line
			(start -0.494 0.25)
			(end 0.504 0.25)
			(stroke
				(width 0.15)
				(type solid)
			)
			(layer "B.Fab")
		)
		(fp_line
			(start 0.504 0.25)
			(end 0.504 -0.248)
			(stroke
				(width 0.15)
				(type solid)
			)
			(layer "B.Fab")
		)
		(fp_line
			(start -0.494 -0.248)
			(end -0.494 0.25)
			(stroke
				(width 0.15)
				(type solid)
			)
			(layer "B.Fab")
		)
		(fp_line
			(start 0.504 -0.248)
			(end -0.494 -0.248)
			(stroke
				(width 0.15)
				(type solid)
			)
			(layer "B.Fab")
		)
		(fp_text user "Author: Antmicro"
			(at -0.939 -3.399 90)
			(layer "B.Fab")
			(effects
				(font
					(size 0.7 0.7)
					(thickness 0.15)
				)
				(justify left bottom mirror)
			)
		)
		(fp_text user "${REFERENCE}"
			(at -0.939 -4.599 90)
			(layer "B.Fab")
			(effects
				(font
					(size 0.7 0.7)
					(thickness 0.15)
				)
				(justify left bottom mirror)
			)
		)
		(fp_text user "License: Apache-2.0"
			(at -0.939 -5.799 90)
			(layer "B.Fab")
			(effects
				(font
					(size 0.7 0.7)
					(thickness 0.15)
				)
				(justify left bottom mirror)
			)
		)
		(pad "1" smd roundrect
			(at -0.48 0 270)
			(size 0.59 0.64)
			(layers "B.Cu" "B.Mask" "B.Paste")
			(roundrect_rratio 0.25)
			(net 797 "+1V8")
			(pintype "passive")
		)
		(pad "2" smd roundrect
			(at 0.48 0 270)
			(size 0.59 0.64)
			(layers "B.Cu" "B.Mask" "B.Paste")
			(roundrect_rratio 0.25)
			(net 1 "GND")
			(pintype "passive")
		)
	)
	(footprint "antmicro-footprints:R_0402_1005Metric"
		(layer "B.Cu")
		(at 217.89 153.1205 180)
		(descr "Resistor SMD 0402")
		(tags "resistor SMD 0402")
		(property "Reference" "R7"
			(at 1.16 -0.47 0)
			(layer "B.SilkS")
			(effects
				(font
					(size 0.7 0.7)
					(thickness 0.15)
				)
				(justify left bottom mirror)
			)
		)
		(property "Value" "R_22R_0402"
			(at -1.011843 -1.772047 0)
			(layer "B.Fab")
			(effects
				(font
					(size 0.7 0.7)
					(thickness 0.15)
				)
				(justify left bottom mirror)
			)
		)
		(property "Datasheet" "https://www.bourns.com/docs/product-datasheets/cr.pdf"
			(at 0 0 180)
			(layer "F.Fab")
			(hide yes)
			(effects
				(font
					(size 1.27 1.27)
					(thickness 0.15)
				)
			)
		)
		(property "Manufacturer" "Bourns"
			(at 0 0 180)
			(unlocked yes)
			(layer "B.Fab")
			(hide yes)
			(effects
				(font
					(size 1 1)
					(thickness 0.15)
				)
				(justify mirror)
			)
		)
		(property "MPN" "CR0402-FX-22R0GLF"
			(at 0 0 180)
			(unlocked yes)
			(layer "B.Fab")
			(hide yes)
			(effects
				(font
					(size 1 1)
					(thickness 0.15)
				)
				(justify mirror)
			)
		)
		(property "Val" "22R"
			(at 0 0 180)
			(unlocked yes)
			(layer "B.Fab")
			(hide yes)
			(effects
				(font
					(size 1 1)
					(thickness 0.15)
				)
				(justify mirror)
			)
		)
		(property "License" "Apache-2.0"
			(at 0 0 180)
			(unlocked yes)
			(layer "B.Fab")
			(hide yes)
			(effects
				(font
					(size 1 1)
					(thickness 0.15)
				)
				(justify mirror)
			)
		)
		(property "Author" "Antmicro"
			(at 0 0 180)
			(unlocked yes)
			(layer "B.Fab")
			(hide yes)
			(effects
				(font
					(size 1 1)
					(thickness 0.15)
				)
				(justify mirror)
			)
		)
		(property "Tolerance" "1%"
			(at 0 0 180)
			(unlocked yes)
			(layer "B.Fab")
			(hide yes)
			(effects
				(font
					(size 1 1)
					(thickness 0.15)
				)
				(justify mirror)
			)
		)
		(sheetname "/HyperRAM + QSPI Flash/")
		(sheetfile "hyperram-flash.kicad_sch")
		(attr smd)
		(fp_rect
			(start -0.925 0.47)
			(end 0.925 -0.47)
			(stroke
				(width 0.05)
				(type default)
			)
			(fill no)
			(layer "B.CrtYd")
		)
		(fp_rect
			(start -0.5 0.25)
			(end 0.5 -0.25)
			(stroke
				(width 0.15)
				(type solid)
			)
			(fill no)
			(layer "B.Fab")
		)
		(fp_text user "License: Apache-2.0"
			(at -0.95 -5.169 0)
			(layer "B.Fab")
			(effects
				(font
					(size 0.7 0.7)
					(thickness 0.15)
				)
				(justify left bottom mirror)
			)
		)
		(fp_text user "Author: Antmicro"
			(at -0.95 -4.169 0)
			(layer "B.Fab")
			(effects
				(font
					(size 0.7 0.7)
					(thickness 0.15)
				)
				(justify left bottom mirror)
			)
		)
		(fp_text user "${REFERENCE}"
			(at -0.95 -3.168 0)
			(layer "B.Fab")
			(effects
				(font
					(size 0.7 0.7)
					(thickness 0.15)
				)
				(justify left bottom mirror)
			)
		)
		(pad "1" smd roundrect
			(at -0.48 0 180)
			(size 0.59 0.64)
			(layers "B.Cu" "B.Mask" "B.Paste")
			(roundrect_rratio 0.25)
			(net 282 "/HyperRAM + QSPI Flash/IO1")
			(pintype "passive")
		)
		(pad "2" smd roundrect
			(at 0.48 0 180)
			(size 0.59 0.64)
			(layers "B.Cu" "B.Mask" "B.Paste")
			(roundrect_rratio 0.25)
			(net 352 "/FPGA Config/FLASH.IO1")
			(pintype "passive")
		)
	)
	(footprint "antmicro-footprints:C_0402_1005Metric_EIA"
		(layer "B.Cu")
		(at 181.5 156)
		(descr "Capacitor SMD 0402 (1005 Metric), square (rectangular) end terminal, IPC_7351 nominal, (Body size source: IPC-SM-782 page 76, https://www.pcb-3d.com/wordpress/wp-content/uploads/ipc-sm-782a_amendment_1_and_2.pdf)")
		(tags "capacitor 0402")
		(property "Reference" "C16"
			(at -3.1 0.45 0)
			(layer "B.SilkS")
			(effects
				(font
					(size 0.7 0.7)
					(thickness 0.15)
				)
				(justify right bottom mirror)
			)
		)
		(property "Value" "C_10u_10V_0402"
			(at 0 -1.169 0)
			(layer "B.Fab")
			(effects
				(font
					(size 0.7 0.7)
					(thickness 0.15)
				)
				(justify right bottom mirror)
			)
		)
		(property "Datasheet" "https://www.murata.com/products/productdetail?partno=GRM155R61A106ME11%23"
			(at 0 0 0)
			(layer "F.Fab")
			(hide yes)
			(effects
				(font
					(size 1.27 1.27)
					(thickness 0.15)
				)
			)
		)
		(property "MPN" "GRM155R61A106ME11D"
			(at 0 0 0)
			(unlocked yes)
			(layer "B.Fab")
			(hide yes)
			(effects
				(font
					(size 1 1)
					(thickness 0.15)
				)
				(justify mirror)
			)
		)
		(property "Manufacturer" "Murata"
			(at 0 0 0)
			(unlocked yes)
			(layer "B.Fab")
			(hide yes)
			(effects
				(font
					(size 1 1)
					(thickness 0.15)
				)
				(justify mirror)
			)
		)
		(property "License" "Apache-2.0"
			(at 0 0 0)
			(unlocked yes)
			(layer "B.Fab")
			(hide yes)
			(effects
				(font
					(size 1 1)
					(thickness 0.15)
				)
				(justify mirror)
			)
		)
		(property "Author" "Antmicro"
			(at 0 0 0)
			(unlocked yes)
			(layer "B.Fab")
			(hide yes)
			(effects
				(font
					(size 1 1)
					(thickness 0.15)
				)
				(justify mirror)
			)
		)
		(property "Val" "10u"
			(at 0 0 0)
			(unlocked yes)
			(layer "B.Fab")
			(hide yes)
			(effects
				(font
					(size 1 1)
					(thickness 0.15)
				)
				(justify mirror)
			)
		)
		(property "Voltage" "10V"
			(at 0 0 0)
			(unlocked yes)
			(layer "B.Fab")
			(hide yes)
			(effects
				(font
					(size 1 1)
					(thickness 0.15)
				)
				(justify mirror)
			)
		)
		(property "Dielectric" "X5R"
			(at 0 0 0)
			(unlocked yes)
			(layer "B.Fab")
			(hide yes)
			(effects
				(font
					(size 1 1)
					(thickness 0.15)
				)
				(justify mirror)
			)
		)
		(sheetname "/FPGA power/")
		(sheetfile "fpga-power.kicad_sch")
		(attr smd)
		(fp_rect
			(start -0.95 0.45)
			(end 0.95 -0.45)
			(stroke
				(width 0.05)
				(type default)
			)
			(fill no)
			(layer "B.CrtYd")
		)
		(fp_line
			(start -0.5 -0.248)
			(end -0.5 0.25)
			(stroke
				(width 0.15)
				(type solid)
			)
			(layer "B.Fab")
		)
		(fp_line
			(start -0.5 0.25)
			(end 0.498 0.25)
			(stroke
				(width 0.15)
				(type solid)
			)
			(layer "B.Fab")
		)
		(fp_line
			(start 0.498 -0.248)
			(end -0.5 -0.248)
			(stroke
				(width 0.15)
				(type solid)
			)
			(layer "B.Fab")
		)
		(fp_line
			(start 0.498 0.25)
			(end 0.498 -0.248)
			(stroke
				(width 0.15)
				(type solid)
			)
			(layer "B.Fab")
		)
		(fp_text user "${REFERENCE}"
			(at -0.9656 -3.169 180)
			(layer "B.Fab")
			(effects
				(font
					(size 0.7 0.7)
					(thickness 0.15)
				)
				(justify left bottom mirror)
			)
		)
		(fp_text user "Author: Antmicro"
			(at -0.9656 -5.569 180)
			(layer "B.Fab")
			(effects
				(font
					(size 0.7 0.7)
					(thickness 0.15)
				)
				(justify left bottom mirror)
			)
		)
		(fp_text user "License: Apache-2.0"
			(at -0.9656 -4.369 180)
			(layer "B.Fab")
			(effects
				(font
					(size 0.7 0.7)
					(thickness 0.15)
				)
				(justify left bottom mirror)
			)
		)
		(pad "1" smd roundrect
			(at -0.5 0 270)
			(size 0.6 0.6)
			(layers "B.Cu" "B.Mask" "B.Paste")
			(roundrect_rratio 0.25)
			(net 1 "GND")
			(pintype "passive")
		)
		(pad "2" smd roundrect
			(at 0.498 0)
			(size 0.6 0.6)
			(layers "B.Cu" "B.Mask" "B.Paste")
			(roundrect_rratio 0.25)
			(net 151 "+3V3")
			(pintype "passive")
		)
	)
)
